FILE_TYPE=LIBRARY_PARTS;
primitive 'MMBT39047F';
  pin
    '1':
      PIN_NUMBER='(B)';
      INPUT_LOAD='(-0.01,0.01)';
    '2':
      PIN_NUMBER='(E)';
      BIDIRECTIONAL='TRUE';
      INPUT_LOAD='(-0.01,0.01)';
      OUTPUT_LOAD='(1.0,-1.0)';
    '3':
      PIN_NUMBER='(C)';
      BIDIRECTIONAL='TRUE';
      INPUT_LOAD='(-0.01,0.01)';
      OUTPUT_LOAD='(1.0,-1.0)';
  end_pin;
  body
    PART_NAME='MMBT39047F';
    BODY_NAME='MMBT39047F';
    PHYS_DES_PREFIX='Q';
    CLASS='DISCRETE';
  end_body;
end_primitive;

END.
